#ISCELL
  mstr_misc dns *
  *
#ISCELL
  pure_quanta quanta_title_block_c *
  *
#ISCELL
  standard offpage *
  page184_i1
#CELL
  pure_quanta q_res *
  page184_i10
#ISCELL
  mstr_symbols universal_power *
  page184_i11
#CELL
  pure_quanta q_cap *
  page184_i12
#CELL
  pure_quanta q_cap *
  page184_i13
#CELL
  pure_quanta q_res *
  page184_i14
#CELL
  pure_quanta mpq8633bglec838z *
  page184_i15
#CELL
  pure_quanta q_cap *
  page184_i16
#ISCELL
  pure_quanta_power universal_gnd *
  page184_i19
#CELL
  pure_quanta q_inductor *
  page184_i2
#ISCELL
  pure_quanta_power universal_gnd *
  page184_i20
#CELL
  pure_quanta q_cap *
  page184_i21
#CELL
  pure_quanta q_res *
  page184_i22
#CELL
  pure_quanta q_res *
  page184_i23
#CELL
  pure_quanta q_cap *
  page184_i24
#ISCELL
  mstr_symbols universal_power *
  page184_i25
#CELL
  pure_quanta q_cap *
  page184_i26
#CELL
  pure_quanta q_res *
  page184_i27
#CELL
  pure_quanta q_inductor *
  page184_i28
#CELL
  pure_quanta q_cap *
  page184_i31
#CELL
  pure_quanta q_cap *
  page184_i32
#CELL
  pure_quanta q_cap *
  page184_i33
#ISCELL
  pure_quanta_power universal_gnd *
  page184_i34
#ISCELL
  pure_quanta_power p1v0 *
  page184_i36
#CELL
  pure_quanta q_res *
  page184_i38
#CELL
  pure_quanta q_res *
  page184_i39
#ISCELL
  standard offpage *
  page184_i40
#ISCELL
  standard offpage *
  page184_i41
#CELL
  pure_quanta q_res *
  page184_i42
#ISCELL
  pure_quanta_power universal_gnd *
  page184_i43
#CELL
  pure_quanta q_cap *
  page184_i44
#CELL
  pure_quanta q_cap *
  page184_i45
#ISCELL
  pure_quanta_power universal_gnd *
  page184_i46
#CELL
  pure_quanta q_cap *
  page184_i48
#CELL
  pure_quanta q_cap *
  page184_i5
#ISCELL
  pure_quanta_power universal_gnd *
  page184_i50
#CELL
  pure_quanta q_res *
  page184_i51
#CELL
  pure_quanta q_capp *
  page184_i54
#CELL
  pure_quanta q_res *
  page184_i56
#CELL
  pure_quanta q_cap *
  page184_i57
#ISCELL
  pure_quanta_power universal_gnd *
  page184_i58
#CELL
  pure_quanta q_res *
  page184_i59
#ISCELL
  mstr_symbols p1v0_aux *
  page184_i6
#CELL
  pure_quanta q_cap *
  page184_i60
#ISCELL
  standard offpage *
  page184_i61
#CELL
  pure_quanta q_res *
  page184_i62
#ISCELL
  pure_quanta_power universal_gnd *
  page184_i63
#CELL
  pure_quanta q_cap *
  page184_i64
#ISCELL
  pure_quanta_power universal_gnd *
  page184_i7
#ISCELL
  pure_quanta_power universal_gnd *
  page184_i8
#CELL
  pure_quanta q_cap *
  page184_i9
